# BASEBOARD_FAB2 (Tioga Pass) — schematic netlist excerpt (pin names and nets, part order shuffled) for the footprints in the layout excerpt that follows; sources: Cadence DE-HDL packaged netlist, KiCad conversion of Wiwynn_Tioga_Pass_MB.brd

C7G15  CAP  0.22UF 16V 10% X7R  pkg 0402  page 105 : A = P3E_CPU0_PE2_SS_TXP<10> ; B = P3E_CPU0_PE2_SS_C_TXP<10>
CT57  CAP_A  0.1UF 16V 10% X7R  pkg 0402V  page 210 : A = VR_PVSA_CPU1_BIREF1 ; B = GND
C841  CAP  0.22UF 16V 10% X7R  pkg 0402  page 244 : A = P3E_CPU0_PE1_PCH_TXP<12> ; B = P3E_CPU0_PE1_PCH_CON_TXP<12>

(kicad_pcb
	(version 20260206)
	(generator "pcbnew")
	(generator_version "10.0")
	(general
		(thickness 1.6)
		(legacy_teardrops no)
	)
	(paper "A4")
	(title_block
		(title "Wiwynn_Tioga_Pass_MB.brd")
		(comment 1 "Tioga Pass / footprints 1130-1132 of 4770")
	)
	(layers
		(0 "F.Cu" signal "TOP")
		(4 "In1.Cu" signal "L2GND")
		(6 "In2.Cu" signal "L3")
		(8 "In3.Cu" signal "L4GND")
		(10 "In4.Cu" signal "L5")
		(12 "In5.Cu" signal "L6GND")
		(14 "In6.Cu" signal "L7VCC")
		(16 "In7.Cu" signal "L8VCC")
		(18 "In8.Cu" signal "L9GND")
		(20 "In9.Cu" signal "L10")
		(22 "In10.Cu" signal "L11GND")
		(24 "In11.Cu" signal "L12")
		(26 "In12.Cu" signal "L13GND")
		(2 "B.Cu" signal "BOTTOM")
		(9 "F.Adhes" user "F.Adhesive")
		(11 "B.Adhes" user "B.Adhesive")
		(13 "F.Paste" user "Package Geometry/Pastemask Top")
		(15 "B.Paste" user "Package Geometry/Pastemask Bottom")
		(5 "F.SilkS" user "Ref Des/Silkscreen Top")
		(7 "B.SilkS" user "Ref Des/Silkscreen Bottom")
		(1 "F.Mask" user "Board Geometry/Soldermask Top")
		(3 "B.Mask" user "Board Geometry/Soldermask Bottom")
		(17 "Dwgs.User" user "User.Drawings")
		(19 "Cmts.User" user "User.Comments")
		(21 "Eco1.User" user "User.Eco1")
		(23 "Eco2.User" user "User.Eco2")
		(25 "Edge.Cuts" user "Board Geometry/Outline")
		(27 "Margin" user)
		(31 "F.CrtYd" user "Package Geometry/Place Bound Top")
		(29 "B.CrtYd" user "Package Geometry/Place Bound Bottom")
		(35 "F.Fab" user "Ref Des/Assembly Top")
		(33 "B.Fab" user "Ref Des/Assembly Bottom")
	)
	(footprint ""
		(layer "F.Cu")
		(at 321.16522 -119.26316 -90)
		(property "Reference" "C841"
			(at -0.8382 -0.67818 270)
			(unlocked yes)
			(layer "F.SilkS")
			(effects
				(font
					(size 0.4064 0.254)
					(thickness 0.1524)
				)
				(justify left)
			)
		)
		(property "Value" ""
			(at 0 0 270)
			(layer "F.Fab")
			(effects
				(font
					(size 1.27 1.27)
				)
			)
		)
		(duplicate_pad_numbers_are_jumpers no)
		(fp_poly
			(pts
				(xy 0.3048 -0.1016) (xy 0.3048 0.9906) (xy -0.3048 0.9906) (xy -0.3048 -0.1016)
			)
			(stroke
				(width 0)
				(type default)
			)
			(fill no)
			(layer "F.CrtYd")
		)
		(fp_line
			(start -0.3048 0.9906)
			(end 0.3048 0.9906)
			(stroke
				(width 0.1)
				(type default)
			)
			(layer "F.Fab")
		)
		(fp_line
			(start 0.3048 0.9906)
			(end 0.3048 -0.1016)
			(stroke
				(width 0.1)
				(type default)
			)
			(layer "F.Fab")
		)
		(fp_line
			(start -0.3048 -0.1016)
			(end -0.3048 0.9906)
			(stroke
				(width 0.1)
				(type default)
			)
			(layer "F.Fab")
		)
		(fp_line
			(start 0.3048 -0.1016)
			(end -0.3048 -0.1016)
			(stroke
				(width 0.1)
				(type default)
			)
			(layer "F.Fab")
		)
		(pad "1" smd rect
			(at 0 0 270)
			(size 0.508 0.508)
			(layers "F.Cu" "F.Mask" "F.Paste")
			(net "P3E_CPU0_PE1_PCH_TXP<12>")
		)
		(pad "2" smd rect
			(at 0 0.889 270)
			(size 0.508 0.508)
			(layers "F.Cu" "F.Mask" "F.Paste")
			(net "P3E_CPU0_PE1_PCH_CON_TXP<12>")
		)
		(zone
			(layer "F.Cu")
			(hatch none 0.5)
			(connect_pads
				(clearance 0)
			)
			(min_thickness 0.25)
			(keepout
				(tracks not_allowed)
				(vias allowed)
				(pads allowed)
				(copperpour not_allowed)
				(footprints allowed)
			)
			(placement
				(enabled no)
				(sheetname "")
			)
			(fill
				(thermal_gap 0.5)
				(thermal_bridge_width 0.5)
				(island_removal_mode 0)
			)
			(polygon
				(pts
					(xy 320.53022 -119.51716) (xy 320.53022 -119.00916) (xy 320.91122 -119.00916) (xy 320.91122 -119.51716)
				)
			)
		)
		(zone
			(layer "F.Cu")
			(hatch none 0.5)
			(connect_pads
				(clearance 0)
			)
			(min_thickness 0.25)
			(keepout
				(tracks allowed)
				(vias not_allowed)
				(pads allowed)
				(copperpour not_allowed)
				(footprints allowed)
			)
			(placement
				(enabled no)
				(sheetname "")
			)
			(fill
				(thermal_gap 0.5)
				(thermal_bridge_width 0.5)
				(island_removal_mode 0)
			)
			(polygon
				(pts
					(xy 320.91122 -119.51716) (xy 320.91122 -119.00916) (xy 320.53022 -119.00916) (xy 320.53022 -119.51716)
				)
			)
		)
	)
	(footprint ""
		(layer "F.Cu")
		(at 374.278144 -10.916158)
		(property "Reference" "C7G15"
			(at 0 0 0)
			(layer "F.SilkS")
			(hide yes)
			(effects
				(font
					(size 1.27 1.27)
				)
			)
		)
		(property "Value" ""
			(at 0 0 0)
			(layer "F.Fab")
			(effects
				(font
					(size 1.27 1.27)
				)
			)
		)
		(duplicate_pad_numbers_are_jumpers no)
		(fp_rect
			(start -0.3048 0.9906)
			(end 0.3048 -0.1016)
			(stroke
				(width 0)
				(type default)
			)
			(fill no)
			(layer "F.CrtYd")
		)
		(fp_line
			(start -0.3048 -0.1016)
			(end -0.3048 0.9906)
			(stroke
				(width 0.1)
				(type default)
			)
			(layer "F.Fab")
		)
		(fp_line
			(start -0.3048 0.9906)
			(end 0.3048 0.9906)
			(stroke
				(width 0.1)
				(type default)
			)
			(layer "F.Fab")
		)
		(fp_line
			(start 0.3048 -0.1016)
			(end -0.3048 -0.1016)
			(stroke
				(width 0.1)
				(type default)
			)
			(layer "F.Fab")
		)
		(fp_line
			(start 0.3048 0.9906)
			(end 0.3048 -0.1016)
			(stroke
				(width 0.1)
				(type default)
			)
			(layer "F.Fab")
		)
		(pad "1" smd rect
			(at 0 0)
			(size 0.508 0.508)
			(layers "F.Cu" "F.Mask" "F.Paste")
			(net "P3E_CPU0_PE2_SS_TXP<10>")
		)
		(pad "2" smd rect
			(at 0 0.889)
			(size 0.508 0.508)
			(layers "F.Cu" "F.Mask" "F.Paste")
			(net "P3E_CPU0_PE2_SS_C_TXP<10>")
		)
		(zone
			(layer "F.Cu")
			(hatch none 0.5)
			(connect_pads
				(clearance 0)
			)
			(min_thickness 0.25)
			(keepout
				(tracks allowed)
				(vias not_allowed)
				(pads allowed)
				(copperpour not_allowed)
				(footprints allowed)
			)
			(placement
				(enabled no)
				(sheetname "")
			)
			(fill
				(thermal_gap 0.5)
				(thermal_bridge_width 0.5)
				(island_removal_mode 0)
			)
			(polygon
				(pts
					(xy 374.024144 -10.281158) (xy 374.532144 -10.281158) (xy 374.532144 -10.662158) (xy 374.024144 -10.662158)
				)
			)
		)
		(zone
			(layer "F.Cu")
			(hatch none 0.5)
			(connect_pads
				(clearance 0)
			)
			(min_thickness 0.25)
			(keepout
				(tracks not_allowed)
				(vias allowed)
				(pads allowed)
				(copperpour not_allowed)
				(footprints allowed)
			)
			(placement
				(enabled no)
				(sheetname "")
			)
			(fill
				(thermal_gap 0.5)
				(thermal_bridge_width 0.5)
				(island_removal_mode 0)
			)
			(polygon
				(pts
					(xy 374.024144 -10.281158) (xy 374.532144 -10.281158) (xy 374.532144 -10.662158) (xy 374.024144 -10.662158)
				)
			)
		)
	)
	(footprint ""
		(layer "F.Cu")
		(at 29.965904 -94.604332)
		(property "Reference" "CT57"
			(at -3.37693 1.9304 90)
			(unlocked yes)
			(layer "F.SilkS")
			(effects
				(font
					(size 0.7874 0.5842)
					(thickness 0.1524)
				)
				(justify left)
			)
		)
		(property "Value" ""
			(at 0 0 0)
			(layer "F.Fab")
			(effects
				(font
					(size 1.27 1.27)
				)
			)
		)
		(duplicate_pad_numbers_are_jumpers no)
		(fp_poly
			(pts
				(xy 0.3048 -0.1016) (xy 0.3048 0.9906) (xy -0.3048 0.9906) (xy -0.3048 -0.1016)
			)
			(stroke
				(width 0)
				(type default)
			)
			(fill no)
			(layer "F.CrtYd")
		)
		(fp_line
			(start -0.3048 -0.1016)
			(end -0.3048 0.9906)
			(stroke
				(width 0.1)
				(type default)
			)
			(layer "F.Fab")
		)
		(fp_line
			(start -0.3048 0.9906)
			(end 0.3048 0.9906)
			(stroke
				(width 0.1)
				(type default)
			)
			(layer "F.Fab")
		)
		(fp_line
			(start 0.3048 -0.1016)
			(end -0.3048 -0.1016)
			(stroke
				(width 0.1)
				(type default)
			)
			(layer "F.Fab")
		)
		(fp_line
			(start 0.3048 0.9906)
			(end 0.3048 -0.1016)
			(stroke
				(width 0.1)
				(type default)
			)
			(layer "F.Fab")
		)
		(pad "1" smd rect
			(at 0 0)
			(size 0.508 0.508)
			(layers "F.Cu" "F.Mask" "F.Paste")
			(net "VR_PVSA_CPU1_BIREF1")
		)
		(pad "2" smd rect
			(at 0 0.889)
			(size 0.508 0.508)
			(layers "F.Cu" "F.Mask" "F.Paste")
			(net "GND")
		)
		(zone
			(layer "F.Cu")
			(hatch none 0.5)
			(connect_pads
				(clearance 0)
			)
			(min_thickness 0.25)
			(keepout
				(tracks allowed)
				(vias not_allowed)
				(pads allowed)
				(copperpour not_allowed)
				(footprints allowed)
			)
			(placement
				(enabled no)
				(sheetname "")
			)
			(fill
				(thermal_gap 0.5)
				(thermal_bridge_width 0.5)
				(island_removal_mode 0)
			)
			(polygon
				(pts
					(xy 29.711904 -94.350332) (xy 30.219904 -94.350332) (xy 30.219904 -93.969332) (xy 29.711904 -93.969332)
				)
			)
		)
		(zone
			(layer "F.Cu")
			(hatch none 0.5)
			(connect_pads
				(clearance 0)
			)
			(min_thickness 0.25)
			(keepout
				(tracks not_allowed)
				(vias allowed)
				(pads allowed)
				(copperpour not_allowed)
				(footprints allowed)
			)
			(placement
				(enabled no)
				(sheetname "")
			)
			(fill
				(thermal_gap 0.5)
				(thermal_bridge_width 0.5)
				(island_removal_mode 0)
			)
			(polygon
				(pts
					(xy 29.711904 -93.969332) (xy 30.219904 -93.969332) (xy 30.219904 -94.350332) (xy 29.711904 -94.350332)
				)
			)
		)
	)
)
